# TIMECARD (Time Appliance Project (Time Card)) — schematic netlist excerpt (pin names and nets, part order shuffled) for the footprints in the layout excerpt that follows; sources: Cadence DE-HDL packaged netlist, KiCad conversion of R4006-B0001-02_R01.brd

R418  RESISTOR  4.7KOHM 1%  pkg SMC_0402R_H016  page 17 : \1\ = XP3R3V_FPGA ; \2\ = UNNAMED_6_LM75BDPTSSOP8_I59_A0
R292  RESISTOR  10KOHM 1%  pkg SMC_0402R_H016  page 25 : \1\ = XP3R3V_FPGA ; \2\ = FPGA_IO_4

(kicad_pcb
	(version 20260206)
	(generator "pcbnew")
	(generator_version "10.0")
	(general
		(thickness 1.6)
		(legacy_teardrops no)
	)
	(paper "A4")
	(title_block
		(title "timecard-production-celestica-r4006 — R4006-B0001-02_R01.brd")
		(comment 1 "Time Appliance Project (Time Card) / footprints 164-165 of 1113")
	)
	(layers
		(0 "F.Cu" signal "TOP")
		(4 "In1.Cu" signal "L02_GND1")
		(6 "In2.Cu" signal "L03_SIG1")
		(8 "In3.Cu" signal "L04_GND2")
		(10 "In4.Cu" signal "L05_VCC1")
		(12 "In5.Cu" signal "L06_VCC2")
		(14 "In6.Cu" signal "L07_GND3")
		(16 "In7.Cu" signal "L08_SIG2")
		(18 "In8.Cu" signal "L09_GND4")
		(2 "B.Cu" signal "BOTTOM")
		(9 "F.Adhes" user "F.Adhesive")
		(11 "B.Adhes" user "B.Adhesive")
		(13 "F.Paste" user "Package Geometry/Pastemask Top")
		(15 "B.Paste" user "Package Geometry/Pastemask Bottom")
		(5 "F.SilkS" user "Ref Des/Silkscreen Top")
		(7 "B.SilkS" user "Ref Des/Silkscreen Bottom")
		(1 "F.Mask" user "Board Geometry/Soldermask Top")
		(3 "B.Mask" user "Board Geometry/Soldermask Bottom")
		(17 "Dwgs.User" user "User.Drawings")
		(19 "Cmts.User" user "User.Comments")
		(21 "Eco1.User" user "User.Eco1")
		(23 "Eco2.User" user "User.Eco2")
		(25 "Edge.Cuts" user "Board Geometry/Outline")
		(27 "Margin" user)
		(31 "F.CrtYd" user "Package Geometry/Place Bound Top")
		(29 "B.CrtYd" user "Package Geometry/Place Bound Bottom")
		(35 "F.Fab" user "Ref Des/Assembly Top")
		(33 "B.Fab" user "Ref Des/Assembly Bottom")
	)
	(footprint ""
		(layer "F.Cu")
		(at 102.5398 -64.2874 -90)
		(property "Reference" "R292"
			(at 2.8194 -0.75057 90)
			(unlocked yes)
			(layer "F.SilkS")
			(effects
				(font
					(size 0.7874 0.5842)
					(thickness 0.1524)
				)
			)
		)
		(property "Value" "VAL*"
			(at 0.02032 2.13233 270)
			(unlocked yes)
			(layer "F.Fab")
			(hide yes)
			(effects
				(font
					(size 0.7874 0.5842)
					(thickness 0.1524)
				)
			)
		)
		(property "Tolerance" "TOL*"
			(at 0.044704 3.05435 270)
			(unlocked yes)
			(layer "Cmts.User")
			(hide yes)
			(effects
				(font
					(size 0.7874 0.5842)
					(thickness 0.1524)
				)
			)
		)
		(property "User Part Number" "PARTNUM*"
			(at 0.02032 4.024884 270)
			(unlocked yes)
			(layer "Cmts.User")
			(hide yes)
			(effects
				(font
					(size 0.7874 0.5842)
					(thickness 0.1524)
				)
			)
		)
		(property "Device Type" "RESISTOR-G155-11002-01,10KOHM,A"
			(at 0.008382 1.210564 270)
			(unlocked yes)
			(layer "F.Fab")
			(hide yes)
			(effects
				(font
					(size 0.7874 0.5842)
					(thickness 0.1524)
				)
			)
		)
		(duplicate_pad_numbers_are_jumpers no)
		(fp_line
			(start -1.143 0.5588)
			(end 1.143 0.5588)
			(stroke
				(width 0.1)
				(type default)
			)
			(layer "F.SilkS")
		)
		(fp_line
			(start 1.143 0.5588)
			(end 1.143 -0.5588)
			(stroke
				(width 0.1)
				(type default)
			)
			(layer "F.SilkS")
		)
		(fp_line
			(start -1.143 -0.5588)
			(end -1.143 0.5588)
			(stroke
				(width 0.1)
				(type default)
			)
			(layer "F.SilkS")
		)
		(fp_line
			(start 1.143 -0.5588)
			(end -1.143 -0.5588)
			(stroke
				(width 0.1)
				(type default)
			)
			(layer "F.SilkS")
		)
		(fp_rect
			(start 1.143 0.5588)
			(end -1.143 -0.5588)
			(stroke
				(width 0)
				(type default)
			)
			(fill no)
			(layer "F.CrtYd")
		)
		(fp_line
			(start -0.508 0.3048)
			(end 0.508 0.3048)
			(stroke
				(width 0.1)
				(type default)
			)
			(layer "F.Fab")
		)
		(fp_line
			(start 0.508 0.3048)
			(end 0.508 -0.3048)
			(stroke
				(width 0.1)
				(type default)
			)
			(layer "F.Fab")
		)
		(fp_line
			(start -0.508 -0.3048)
			(end -0.508 0.3048)
			(stroke
				(width 0.1)
				(type default)
			)
			(layer "F.Fab")
		)
		(fp_line
			(start 0.508 -0.3048)
			(end -0.508 -0.3048)
			(stroke
				(width 0.1)
				(type default)
			)
			(layer "F.Fab")
		)
		(pad "1" smd rect
			(at -0.5334 0 270)
			(size 0.7112 0.6096)
			(layers "F.Cu" "F.Mask" "F.Paste")
			(net "XP3R3V_FPGA")
		)
		(pad "2" smd rect
			(at 0.5334 0 270)
			(size 0.7112 0.6096)
			(layers "F.Cu" "F.Mask" "F.Paste")
			(net "FPGA_IO_4")
		)
		(zone
			(layer "F.Cu")
			(hatch none 0.5)
			(connect_pads
				(clearance 0)
			)
			(min_thickness 0.25)
			(keepout
				(tracks allowed)
				(vias not_allowed)
				(pads allowed)
				(copperpour not_allowed)
				(footprints allowed)
			)
			(placement
				(enabled no)
				(sheetname "")
			)
			(fill
				(thermal_gap 0.5)
				(thermal_bridge_width 0.5)
				(island_removal_mode 0)
			)
			(polygon
				(pts
					(xy 102.235 -64.2112) (xy 102.8446 -64.2112) (xy 102.8446 -64.3636) (xy 102.235 -64.3636)
				)
			)
		)
	)
	(footprint ""
		(layer "F.Cu")
		(at 55.1942 -74.9808 90)
		(property "Reference" "R418"
			(at -0.5588 4.28117 90)
			(unlocked yes)
			(layer "F.SilkS")
			(effects
				(font
					(size 0.7874 0.5842)
					(thickness 0.1524)
				)
			)
		)
		(property "Value" "VAL*"
			(at 0.02032 2.13233 90)
			(unlocked yes)
			(layer "F.Fab")
			(hide yes)
			(effects
				(font
					(size 0.7874 0.5842)
					(thickness 0.1524)
				)
			)
		)
		(property "Device Type" "RESISTOR-G155-14701-01,4.7KOHMA"
			(at 0.008382 1.210564 90)
			(unlocked yes)
			(layer "F.Fab")
			(hide yes)
			(effects
				(font
					(size 0.7874 0.5842)
					(thickness 0.1524)
				)
			)
		)
		(property "User Part Number" "PARTNUM*"
			(at 0.02032 4.024884 90)
			(unlocked yes)
			(layer "Cmts.User")
			(hide yes)
			(effects
				(font
					(size 0.7874 0.5842)
					(thickness 0.1524)
				)
			)
		)
		(property "Tolerance" "TOL*"
			(at 0.044704 3.05435 90)
			(unlocked yes)
			(layer "Cmts.User")
			(hide yes)
			(effects
				(font
					(size 0.7874 0.5842)
					(thickness 0.1524)
				)
			)
		)
		(duplicate_pad_numbers_are_jumpers no)
		(fp_line
			(start 1.143 -0.5588)
			(end -1.143 -0.5588)
			(stroke
				(width 0.1)
				(type default)
			)
			(layer "F.SilkS")
		)
		(fp_line
			(start -1.143 -0.5588)
			(end -1.143 0.5588)
			(stroke
				(width 0.1)
				(type default)
			)
			(layer "F.SilkS")
		)
		(fp_line
			(start 1.143 0.5588)
			(end 1.143 -0.5588)
			(stroke
				(width 0.1)
				(type default)
			)
			(layer "F.SilkS")
		)
		(fp_line
			(start -1.143 0.5588)
			(end 1.143 0.5588)
			(stroke
				(width 0.1)
				(type default)
			)
			(layer "F.SilkS")
		)
		(fp_rect
			(start -1.143 0.5588)
			(end 1.143 -0.5588)
			(stroke
				(width 0)
				(type default)
			)
			(fill no)
			(layer "F.CrtYd")
		)
		(fp_line
			(start 0.508 -0.3048)
			(end -0.508 -0.3048)
			(stroke
				(width 0.1)
				(type default)
			)
			(layer "F.Fab")
		)
		(fp_line
			(start -0.508 -0.3048)
			(end -0.508 0.3048)
			(stroke
				(width 0.1)
				(type default)
			)
			(layer "F.Fab")
		)
		(fp_line
			(start 0.508 0.3048)
			(end 0.508 -0.3048)
			(stroke
				(width 0.1)
				(type default)
			)
			(layer "F.Fab")
		)
		(fp_line
			(start -0.508 0.3048)
			(end 0.508 0.3048)
			(stroke
				(width 0.1)
				(type default)
			)
			(layer "F.Fab")
		)
		(pad "1" smd rect
			(at -0.5334 0 90)
			(size 0.7112 0.6096)
			(layers "F.Cu" "F.Mask" "F.Paste")
			(net "XP3R3V_FPGA")
		)
		(pad "2" smd rect
			(at 0.5334 0 90)
			(size 0.7112 0.6096)
			(layers "F.Cu" "F.Mask" "F.Paste")
			(net "UNNAMED_6_LM75BDPTSSOP8_I59_A0")
		)
		(zone
			(layer "F.Cu")
			(hatch none 0.5)
			(connect_pads
				(clearance 0)
			)
			(min_thickness 0.25)
			(keepout
				(tracks not_allowed)
				(vias allowed)
				(pads allowed)
				(copperpour not_allowed)
				(footprints allowed)
			)
			(placement
				(enabled no)
				(sheetname "")
			)
			(fill
				(thermal_gap 0.5)
				(thermal_bridge_width 0.5)
				(island_removal_mode 0)
			)
			(polygon
				(pts
					(xy 55.499 -74.9046) (xy 55.499 -75.057) (xy 54.8894 -75.057) (xy 54.8894 -74.9046)
				)
			)
		)
		(zone
			(layer "F.Cu")
			(hatch none 0.5)
			(connect_pads
				(clearance 0)
			)
			(min_thickness 0.25)
			(keepout
				(tracks allowed)
				(vias not_allowed)
				(pads allowed)
				(copperpour not_allowed)
				(footprints allowed)
			)
			(placement
				(enabled no)
				(sheetname "")
			)
			(fill
				(thermal_gap 0.5)
				(thermal_bridge_width 0.5)
				(island_removal_mode 0)
			)
			(polygon
				(pts
					(xy 55.499 -74.9046) (xy 55.499 -75.057) (xy 54.8894 -75.057) (xy 54.8894 -74.9046)
				)
			)
		)
	)
)
